FILE_TYPE = CONNECTIVITY;
{Allegro Design Entry HDL 17.2-2016 S081 (4005846) 1/11/2022}
"PAGE_NUMBER" = 42;
0"NC";
1"P3V3_AUX\g";
2"P3V3_AUX\g";
3"GND\g";
4"FM_ADR_TRIGGER_N";
5"FM_JTAG_BMC_MUX_SEL";
6"PWRGD_DSW_PWROK";
7"FM_BMC_CRASHLOG_TRIG_N";
8"FM_P12V_HSC_ENABLE";
9"BMC_CPLD_GPIO_13";
10"BMC_CPLD_GPIO_12";
11"BMC_CPLD_GPIO_8";
12"BMC_CPLD_GPIO_7";
13"BMC_ID_BEEP_SEL";
14"BMC_CPLD_GPIO_2";
15"RST_BMC_SELF_HW_R2";
%"Q_RES"
"1","(8500,1450)","0","pure_quanta","I13";
;
VALUE"4.7K"
MATERIAL"CHIP"
PACK_TYPE"0402LF"
WATTAGE"1/16W"
TOLERANCE"1%"
CDS_LIB"pure_quanta"
PART_NUMBER"CS24702FB06"
LOCATION"R621"
$SEC"1"
CDS_SEC"1";
"B"
$PN"2"8;
"A"
$PN"1"2;
%"Q_RES"
"1","(8500,2500)","0","pure_quanta","I27";
;
VALUE"4.7K"
MATERIAL"CHIP"
PACK_TYPE"0402LF"
WATTAGE"1/16W"
TOLERANCE"1%"
CDS_LIB"pure_quanta"
PART_NUMBER"CS24702FB06"
LOCATION"R608"
$SEC"1"
CDS_SEC"1";
"B"
$PN"2"9;
"A"
$PN"1"2;
%"Q_RES"
"1","(8500,2650)","0","pure_quanta","I29";
;
MATERIAL"CHIP"
VALUE"4.7K"
PACK_TYPE"0402LF"
WATTAGE"1/16W"
TOLERANCE"1%"
CDS_LIB"pure_quanta"
PART_NUMBER"CS24702FB06"
LOCATION"R607"
$SEC"1"
CDS_SEC"1";
"B"
$PN"2"10;
"A"
$PN"1"2;
%"UNIVERSAL_POWER"
"1","(8050,4450)","0","logical_power","I3";
;
HDL_POWER"P3V3_AUX"
CDS_LIB"logical_power";
"A"2;
%"Q_RES"
"1","(8500,3250)","0","pure_quanta","I37";
;
VALUE"4.7K"
MATERIAL"EMPTY"
PACK_TYPE"0402LF"
WATTAGE"1/16W"
TOLERANCE"1%"
CDS_LIB"pure_quanta"
PART_NUMBER"CS24702FB06"
LOCATION"R595"
$SEC"1"
CDS_SEC"1";
"B"
$PN"2"11;
"A"
$PN"1"2;
%"Q_RES"
"1","(8500,3400)","0","pure_quanta","I39";
;
MATERIAL"EMPTY"
VALUE"4.7K"
PACK_TYPE"0402LF"
WATTAGE"1/16W"
TOLERANCE"1%"
CDS_LIB"pure_quanta"
PART_NUMBER"CS24702FB06"
LOCATION"R593"
$SEC"1"
CDS_SEC"1";
"B"
$PN"2"12;
"A"
$PN"1"2;
%"Q_RES"
"1","(11950,4200)","0","pure_quanta","I53";
;
MATERIAL"EMPTY"
VALUE"4.7K"
PACK_TYPE"0402LF"
WATTAGE"1/16W"
TOLERANCE"1%"
CDS_LIB"pure_quanta"
PART_NUMBER"CS24702FB06"
LOCATION"R641"
$SEC"1"
CDS_SEC"1";
"B"
$PN"2"15;
"A"
$PN"1"1;
%"UNIVERSAL_POWER"
"1","(11500,4400)","0","logical_power","I54";
;
HDL_POWER"P3V3_AUX"
CDS_LIB"logical_power";
"A"1;
%"Q_RES"
"1","(8475,300)","0","pure_quanta","I56";
;
VALUE"4.7K"
MATERIAL"EMPTY"
PACK_TYPE"0402LF"
WATTAGE"1/16W"
TOLERANCE"1%"
CDS_LIB"pure_quanta"
PART_NUMBER"CS24702FB06"
LOCATION"R640"
$SEC"1"
CDS_SEC"1";
"B"
$PN"2"5;
"A"
$PN"1"2;
%"UNIVERSAL_GND"
"1","(8050,-350)","0","logical_power","I57";
;
HDL_POWER"GND"
CDS_LIB"logical_power";
"A"3;
%"Q_RES"
"1","(8475,75)","0","pure_quanta","I58";
;
VALUE"100K"
MATERIAL"CHIP"
PACK_TYPE"0402LF"
WATTAGE"1/16W"
TOLERANCE"1%"
PART_NUMBER"CS41002FB09"
CDS_LIB"pure_quanta"
LOCATION"R642"
$SEC"1"
CDS_SEC"1";
"B"
$PN"2"5;
"A"
$PN"1"3;
%"Q_RES"
"1","(8500,950)","0","pure_quanta","I61";
;
MATERIAL"CHIP"
VALUE"4.7K"
PACK_TYPE"0402LF"
WATTAGE"1/16W"
TOLERANCE"1%"
CDS_LIB"pure_quanta"
PART_NUMBER"CS24702FB06"
LOCATION"R749"
$SEC"1"
CDS_SEC"1";
"B"
$PN"2"7;
"A"
$PN"1"2;
%"Q_RES"
"1","(11950,4050)","0","pure_quanta","I63";
;
VALUE"4.7K"
MATERIAL"CHIP"
PACK_TYPE"0402LF"
WATTAGE"1/16W"
TOLERANCE"1%"
CDS_LIB"pure_quanta"
PART_NUMBER"CS24702FB06"
LOCATION"R835"
$SEC"1"
CDS_SEC"1";
"B"
$PN"2"4;
"A"
$PN"1"1;
%"Q_RES"
"1","(8500,3550)","0","pure_quanta","I65";
;
MATERIAL"CHIP"
VALUE"4.7K"
CDS_LIB"pure_quanta"
PART_NUMBER"CS24702FB06"
TOLERANCE"1%"
WATTAGE"1/16W"
PACK_TYPE"0402LF"
$LOCATION"R319"
CDS_LOCATION"R319"
$SEC"1"
CDS_SEC"1";
"B"
$PN"2"13;
"A"
$PN"1"2;
%"Q_RES"
"1","(8500,4300)","0","pure_quanta","I67";
;
VALUE"4.7K"
MATERIAL"CHIP"
PACK_TYPE"0402LF"
WATTAGE"1/16W"
TOLERANCE"1%"
PART_NUMBER"CS24702FB06"
CDS_LIB"pure_quanta"
LOCATION"R586"
$SEC"1"
CDS_SEC"1";
"B"
$PN"2"14;
"A"
$PN"1"2;
%"Q_RES"
"1","(8500,625)","0","pure_quanta","I7";
;
MATERIAL"CHIP"
VALUE"4.7K"
PACK_TYPE"0402LF"
WATTAGE"1/16W"
TOLERANCE"1%"
CDS_LIB"pure_quanta"
PART_NUMBER"CS24702FB06"
LOCATION"R627"
$SEC"1"
CDS_SEC"1";
"B"
$PN"2"6;
"A"
$PN"1"2;
END.
